# S9S_MB_2U (Grand Teton) — schematic netlist excerpt (pin names and nets, part order shuffled) for the footprints in the layout excerpt that follows; sources: Cadence DE-HDL packaged netlist, KiCad conversion of 03242023_DA0F0TMBIJ0_F0T_Motherboard_J_brd_V01_OCP.brd

R2338  Q_RES  10K 1% EMPTY  pkg 0402LF  page 282 : A = P3V3_AUX ; B = FM_PVNN_MAIN_CPU0_EN
R41  Q_RES  196K 1% CHIP  pkg 0402LF  page 97 : A = PD_CHH_CPU0_DIMM2_SAA ; B = GND

(kicad_pcb
	(version 20260206)
	(generator "pcbnew")
	(generator_version "10.0")
	(general
		(thickness 1.6)
		(legacy_teardrops no)
	)
	(paper "A4")
	(title_block
		(title "03242023_DA0F0TMBIJ0_F0T_Motherboard_J_brd_V01_OCP.brd")
		(comment 1 "Grand Teton / footprints 4362-4363 of 6105")
	)
	(layers
		(0 "F.Cu" signal "TOP")
		(4 "In1.Cu" signal "GND")
		(6 "In2.Cu" signal "IN1")
		(8 "In3.Cu" signal "GND1")
		(10 "In4.Cu" signal "IN2")
		(12 "In5.Cu" signal "GND2")
		(14 "In6.Cu" signal "IN3")
		(16 "In7.Cu" signal "GND3")
		(18 "In8.Cu" signal "VCC")
		(20 "In9.Cu" signal "VCC1")
		(22 "In10.Cu" signal "GND4")
		(24 "In11.Cu" signal "IN4")
		(26 "In12.Cu" signal "GND5")
		(28 "In13.Cu" signal "IN5")
		(30 "In14.Cu" signal "GND6")
		(32 "In15.Cu" signal "IN6")
		(34 "In16.Cu" signal "GND7")
		(2 "B.Cu" signal "BOTTOM")
		(9 "F.Adhes" user "F.Adhesive")
		(11 "B.Adhes" user "B.Adhesive")
		(13 "F.Paste" user "Package Geometry/Pastemask Top")
		(15 "B.Paste" user "Package Geometry/Pastemask Bottom")
		(5 "F.SilkS" user "Ref Des/Silkscreen Top")
		(7 "B.SilkS" user "Ref Des/Silkscreen Bottom")
		(1 "F.Mask" user "Board Geometry/Soldermask Top")
		(3 "B.Mask" user "Board Geometry/Soldermask Bottom")
		(17 "Dwgs.User" user "User.Drawings")
		(19 "Cmts.User" user "User.Comments")
		(21 "Eco1.User" user "User.Eco1")
		(23 "Eco2.User" user "User.Eco2")
		(25 "Edge.Cuts" user "Board Geometry/Outline")
		(27 "Margin" user)
		(31 "F.CrtYd" user "Package Geometry/Place Bound Top")
		(29 "B.CrtYd" user "Package Geometry/Place Bound Bottom")
		(35 "F.Fab" user "Ref Des/Assembly Top")
		(33 "B.Fab" user "Ref Des/Assembly Bottom")
	)
	(footprint ""
		(layer "B.Cu")
		(at 434.354478 -177.15611 -90)
		(property "Reference" "R2338"
			(at 0 0 90)
			(layer "B.SilkS")
			(hide yes)
			(effects
				(font
					(size 1.27 1.27)
				)
				(justify mirror)
			)
		)
		(property "Value" ""
			(at 0 0 90)
			(layer "B.Fab")
			(effects
				(font
					(size 1.27 1.27)
				)
				(justify mirror)
			)
		)
		(duplicate_pad_numbers_are_jumpers no)
		(fp_line
			(start -0.7874 0.4064)
			(end 0.7874 0.4064)
			(stroke
				(width 0.1524)
				(type default)
			)
			(layer "B.SilkS")
		)
		(fp_line
			(start 0.7874 0.4064)
			(end 0.7874 -0.4064)
			(stroke
				(width 0.1524)
				(type default)
			)
			(layer "B.SilkS")
		)
		(fp_line
			(start -0.7874 -0.4064)
			(end -0.7874 0.4064)
			(stroke
				(width 0.1524)
				(type default)
			)
			(layer "B.SilkS")
		)
		(fp_line
			(start 0.7874 -0.4064)
			(end -0.7874 -0.4064)
			(stroke
				(width 0.1524)
				(type default)
			)
			(layer "B.SilkS")
		)
		(fp_line
			(start -0.67945 0.3048)
			(end -0.120396 0.3048)
			(stroke
				(width 0.1)
				(type default)
			)
			(layer "B.Fab")
		)
		(fp_line
			(start -0.120396 0.3048)
			(end -0.120396 0.2794)
			(stroke
				(width 0.1)
				(type default)
			)
			(layer "B.Fab")
		)
		(fp_line
			(start 0.12065 0.3048)
			(end 0.67945 0.3048)
			(stroke
				(width 0.1)
				(type default)
			)
			(layer "B.Fab")
		)
		(fp_line
			(start 0.67945 0.3048)
			(end 0.67945 -0.305054)
			(stroke
				(width 0.1)
				(type default)
			)
			(layer "B.Fab")
		)
		(fp_line
			(start -0.120396 0.2794)
			(end 0.12065 0.2794)
			(stroke
				(width 0.1)
				(type default)
			)
			(layer "B.Fab")
		)
		(fp_line
			(start 0.12065 0.2794)
			(end 0.12065 0.3048)
			(stroke
				(width 0.1)
				(type default)
			)
			(layer "B.Fab")
		)
		(fp_line
			(start -0.12065 -0.2794)
			(end -0.12065 -0.3048)
			(stroke
				(width 0.1)
				(type default)
			)
			(layer "B.Fab")
		)
		(fp_line
			(start 0.12065 -0.2794)
			(end -0.12065 -0.2794)
			(stroke
				(width 0.1)
				(type default)
			)
			(layer "B.Fab")
		)
		(fp_line
			(start -0.67945 -0.3048)
			(end -0.67945 0.3048)
			(stroke
				(width 0.1)
				(type default)
			)
			(layer "B.Fab")
		)
		(fp_line
			(start -0.12065 -0.3048)
			(end -0.67945 -0.3048)
			(stroke
				(width 0.1)
				(type default)
			)
			(layer "B.Fab")
		)
		(fp_line
			(start 0.12065 -0.305054)
			(end 0.12065 -0.2794)
			(stroke
				(width 0.1)
				(type default)
			)
			(layer "B.Fab")
		)
		(fp_line
			(start 0.67945 -0.305054)
			(end 0.12065 -0.305054)
			(stroke
				(width 0.1)
				(type default)
			)
			(layer "B.Fab")
		)
		(pad "1" smd circle
			(at 0.40005 0 90)
			(size 0 0)
			(layers "B.Cu" "B.Mask" "B.Paste")
			(net "P3V3_AUX")
		)
		(pad "2" smd circle
			(at -0.40005 0 90)
			(size 0 0)
			(layers "B.Cu" "B.Mask" "B.Paste")
			(net "FM_PVNN_MAIN_CPU0_EN")
		)
	)
	(footprint ""
		(layer "B.Cu")
		(at 453.850756 -318.704976)
		(property "Reference" "R41"
			(at 0 0 0)
			(layer "B.SilkS")
			(hide yes)
			(effects
				(font
					(size 1.27 1.27)
				)
				(justify mirror)
			)
		)
		(property "Value" ""
			(at 0 0 0)
			(layer "B.Fab")
			(effects
				(font
					(size 1.27 1.27)
				)
				(justify mirror)
			)
		)
		(duplicate_pad_numbers_are_jumpers no)
		(fp_line
			(start -0.7874 -0.4064)
			(end -0.7874 0.4064)
			(stroke
				(width 0.1524)
				(type default)
			)
			(layer "B.SilkS")
		)
		(fp_line
			(start -0.7874 0.4064)
			(end 0.7874 0.4064)
			(stroke
				(width 0.1524)
				(type default)
			)
			(layer "B.SilkS")
		)
		(fp_line
			(start 0.7874 -0.4064)
			(end -0.7874 -0.4064)
			(stroke
				(width 0.1524)
				(type default)
			)
			(layer "B.SilkS")
		)
		(fp_line
			(start 0.7874 0.4064)
			(end 0.7874 -0.4064)
			(stroke
				(width 0.1524)
				(type default)
			)
			(layer "B.SilkS")
		)
		(fp_line
			(start -0.67945 -0.3048)
			(end -0.67945 0.3048)
			(stroke
				(width 0.1)
				(type default)
			)
			(layer "B.Fab")
		)
		(fp_line
			(start -0.67945 0.3048)
			(end -0.120396 0.3048)
			(stroke
				(width 0.1)
				(type default)
			)
			(layer "B.Fab")
		)
		(fp_line
			(start -0.12065 -0.3048)
			(end -0.67945 -0.3048)
			(stroke
				(width 0.1)
				(type default)
			)
			(layer "B.Fab")
		)
		(fp_line
			(start -0.12065 -0.2794)
			(end -0.12065 -0.3048)
			(stroke
				(width 0.1)
				(type default)
			)
			(layer "B.Fab")
		)
		(fp_line
			(start -0.120396 0.2794)
			(end 0.12065 0.2794)
			(stroke
				(width 0.1)
				(type default)
			)
			(layer "B.Fab")
		)
		(fp_line
			(start -0.120396 0.3048)
			(end -0.120396 0.2794)
			(stroke
				(width 0.1)
				(type default)
			)
			(layer "B.Fab")
		)
		(fp_line
			(start 0.12065 -0.305054)
			(end 0.12065 -0.2794)
			(stroke
				(width 0.1)
				(type default)
			)
			(layer "B.Fab")
		)
		(fp_line
			(start 0.12065 -0.2794)
			(end -0.12065 -0.2794)
			(stroke
				(width 0.1)
				(type default)
			)
			(layer "B.Fab")
		)
		(fp_line
			(start 0.12065 0.2794)
			(end 0.12065 0.3048)
			(stroke
				(width 0.1)
				(type default)
			)
			(layer "B.Fab")
		)
		(fp_line
			(start 0.12065 0.3048)
			(end 0.67945 0.3048)
			(stroke
				(width 0.1)
				(type default)
			)
			(layer "B.Fab")
		)
		(fp_line
			(start 0.67945 -0.305054)
			(end 0.12065 -0.305054)
			(stroke
				(width 0.1)
				(type default)
			)
			(layer "B.Fab")
		)
		(fp_line
			(start 0.67945 0.3048)
			(end 0.67945 -0.305054)
			(stroke
				(width 0.1)
				(type default)
			)
			(layer "B.Fab")
		)
		(pad "1" smd circle
			(at 0.40005 0 180)
			(size 0 0)
			(layers "B.Cu" "B.Mask" "B.Paste")
			(net "PD_CHH_CPU0_DIMM2_SAA")
		)
		(pad "2" smd circle
			(at -0.40005 0 180)
			(size 0 0)
			(layers "B.Cu" "B.Mask" "B.Paste")
			(net "GND")
		)
	)
)
